# T6G (Grand Teton) — schematic netlist excerpt (pin names and nets, part order shuffled) for the footprints in the layout excerpt that follows; sources: Cadence DE-HDL packaged netlist, KiCad conversion of 04192023_DAF0TMB3IC0_F0TG_MB_C_brd_V02_OCP.brd

R4210  Q_RES  200K 1% EMPTY  pkg 0402LF  page 235 : A = P3V3_AUX ; B = FM_THERMAL_ALERT_N
R6064  Q_RES  0 5% EMPTY  pkg 0402LF  page 150 : A = UART_CPU0_SCM_LVC3_UART1_RX ; B = UART_CPU0_SCM_LVC3_UART1_R_RX
R1436  Q_RES  1K 1% CHIP  pkg 0201LF  page 185 : A = P1V8_CPU1_RT_1D ; B = SMB_RT_CPU1_P0_ROM_MUX_1D_SDA

(kicad_pcb
	(version 20260206)
	(generator "pcbnew")
	(generator_version "10.0")
	(general
		(thickness 1.6)
		(legacy_teardrops no)
	)
	(paper "A4")
	(title_block
		(title "04192023_DAF0TMB3IC0_F0TG_MB_C_brd_V02_OCP.brd")
		(comment 1 "Grand Teton / footprints 3808-3810 of 8354")
	)
	(layers
		(0 "F.Cu" signal "TOP")
		(4 "In1.Cu" signal "GND")
		(6 "In2.Cu" signal "IN1")
		(8 "In3.Cu" signal "GND1")
		(10 "In4.Cu" signal "IN2")
		(12 "In5.Cu" signal "GND2")
		(14 "In6.Cu" signal "IN3")
		(16 "In7.Cu" signal "GND3")
		(18 "In8.Cu" signal "VCC")
		(20 "In9.Cu" signal "VCC1")
		(22 "In10.Cu" signal "GND4")
		(24 "In11.Cu" signal "IN4")
		(26 "In12.Cu" signal "GND5")
		(28 "In13.Cu" signal "IN5")
		(30 "In14.Cu" signal "GND6")
		(32 "In15.Cu" signal "IN6")
		(34 "In16.Cu" signal "GND7")
		(2 "B.Cu" signal "BOTTOM")
		(9 "F.Adhes" user "F.Adhesive")
		(11 "B.Adhes" user "B.Adhesive")
		(13 "F.Paste" user "Package Geometry/Pastemask Top")
		(15 "B.Paste" user "Package Geometry/Pastemask Bottom")
		(5 "F.SilkS" user "Ref Des/Silkscreen Top")
		(7 "B.SilkS" user "Ref Des/Silkscreen Bottom")
		(1 "F.Mask" user "Board Geometry/Soldermask Top")
		(3 "B.Mask" user "Board Geometry/Soldermask Bottom")
		(17 "Dwgs.User" user "User.Drawings")
		(19 "Cmts.User" user "User.Comments")
		(21 "Eco1.User" user "User.Eco1")
		(23 "Eco2.User" user "User.Eco2")
		(25 "Edge.Cuts" user "Board Geometry/Outline")
		(27 "Margin" user)
		(31 "F.CrtYd" user "Package Geometry/Place Bound Top")
		(29 "B.CrtYd" user "Package Geometry/Place Bound Bottom")
		(35 "F.Fab" user "Ref Des/Assembly Top")
		(33 "B.Fab" user "Ref Des/Assembly Bottom")
	)
	(footprint ""
		(layer "F.Cu")
		(at 186.53252 -19.435572 90)
		(property "Reference" "R6064"
			(at 0 0 90)
			(layer "F.SilkS")
			(hide yes)
			(effects
				(font
					(size 1.27 1.27)
				)
			)
		)
		(property "Value" ""
			(at 0 0 90)
			(layer "F.Fab")
			(effects
				(font
					(size 1.27 1.27)
				)
			)
		)
		(duplicate_pad_numbers_are_jumpers no)
		(fp_line
			(start 0.7874 -0.4064)
			(end 0.7874 0.4064)
			(stroke
				(width 0.1524)
				(type default)
			)
			(layer "F.SilkS")
		)
		(fp_line
			(start -0.7874 -0.4064)
			(end 0.7874 -0.4064)
			(stroke
				(width 0.1524)
				(type default)
			)
			(layer "F.SilkS")
		)
		(fp_line
			(start 0.7874 0.4064)
			(end -0.7874 0.4064)
			(stroke
				(width 0.1524)
				(type default)
			)
			(layer "F.SilkS")
		)
		(fp_line
			(start -0.7874 0.4064)
			(end -0.7874 -0.4064)
			(stroke
				(width 0.1524)
				(type default)
			)
			(layer "F.SilkS")
		)
		(fp_line
			(start -0.12065 -0.305054)
			(end -0.12065 -0.2794)
			(stroke
				(width 0.1)
				(type default)
			)
			(layer "F.Fab")
		)
		(fp_line
			(start -0.67945 -0.305054)
			(end -0.12065 -0.305054)
			(stroke
				(width 0.1)
				(type default)
			)
			(layer "F.Fab")
		)
		(fp_line
			(start 0.67945 -0.3048)
			(end 0.67945 0.3048)
			(stroke
				(width 0.1)
				(type default)
			)
			(layer "F.Fab")
		)
		(fp_line
			(start 0.12065 -0.3048)
			(end 0.67945 -0.3048)
			(stroke
				(width 0.1)
				(type default)
			)
			(layer "F.Fab")
		)
		(fp_line
			(start 0.12065 -0.2794)
			(end 0.12065 -0.3048)
			(stroke
				(width 0.1)
				(type default)
			)
			(layer "F.Fab")
		)
		(fp_line
			(start -0.12065 -0.2794)
			(end 0.12065 -0.2794)
			(stroke
				(width 0.1)
				(type default)
			)
			(layer "F.Fab")
		)
		(fp_line
			(start 0.120396 0.2794)
			(end -0.12065 0.2794)
			(stroke
				(width 0.1)
				(type default)
			)
			(layer "F.Fab")
		)
		(fp_line
			(start -0.12065 0.2794)
			(end -0.12065 0.3048)
			(stroke
				(width 0.1)
				(type default)
			)
			(layer "F.Fab")
		)
		(fp_line
			(start 0.67945 0.3048)
			(end 0.120396 0.3048)
			(stroke
				(width 0.1)
				(type default)
			)
			(layer "F.Fab")
		)
		(fp_line
			(start 0.120396 0.3048)
			(end 0.120396 0.2794)
			(stroke
				(width 0.1)
				(type default)
			)
			(layer "F.Fab")
		)
		(fp_line
			(start -0.12065 0.3048)
			(end -0.67945 0.3048)
			(stroke
				(width 0.1)
				(type default)
			)
			(layer "F.Fab")
		)
		(fp_line
			(start -0.67945 0.3048)
			(end -0.67945 -0.305054)
			(stroke
				(width 0.1)
				(type default)
			)
			(layer "F.Fab")
		)
		(pad "1" smd circle
			(at -0.40005 0 90)
			(size 0 0)
			(layers "F.Cu" "F.Mask" "F.Paste")
			(net "UART_CPU0_SCM_LVC3_UART1_RX")
		)
		(pad "2" smd circle
			(at 0.40005 0 90)
			(size 0 0)
			(layers "F.Cu" "F.Mask" "F.Paste")
			(net "UART_CPU0_SCM_LVC3_UART1_R_RX")
		)
	)
	(footprint ""
		(layer "F.Cu")
		(at 101.346 -412.931102 -90)
		(property "Reference" "R4210"
			(at 0 0 270)
			(layer "F.SilkS")
			(hide yes)
			(effects
				(font
					(size 1.27 1.27)
				)
			)
		)
		(property "Value" ""
			(at 0 0 270)
			(layer "F.Fab")
			(effects
				(font
					(size 1.27 1.27)
				)
			)
		)
		(duplicate_pad_numbers_are_jumpers no)
		(fp_line
			(start -0.7874 0.4064)
			(end -0.7874 -0.4064)
			(stroke
				(width 0.1524)
				(type default)
			)
			(layer "F.SilkS")
		)
		(fp_line
			(start 0.7874 0.4064)
			(end -0.7874 0.4064)
			(stroke
				(width 0.1524)
				(type default)
			)
			(layer "F.SilkS")
		)
		(fp_line
			(start -0.7874 -0.4064)
			(end 0.7874 -0.4064)
			(stroke
				(width 0.1524)
				(type default)
			)
			(layer "F.SilkS")
		)
		(fp_line
			(start 0.7874 -0.4064)
			(end 0.7874 0.4064)
			(stroke
				(width 0.1524)
				(type default)
			)
			(layer "F.SilkS")
		)
		(fp_line
			(start -0.67945 0.3048)
			(end -0.67945 -0.305054)
			(stroke
				(width 0.1)
				(type default)
			)
			(layer "F.Fab")
		)
		(fp_line
			(start -0.12065 0.3048)
			(end -0.67945 0.3048)
			(stroke
				(width 0.1)
				(type default)
			)
			(layer "F.Fab")
		)
		(fp_line
			(start 0.120396 0.3048)
			(end 0.120396 0.2794)
			(stroke
				(width 0.1)
				(type default)
			)
			(layer "F.Fab")
		)
		(fp_line
			(start 0.67945 0.3048)
			(end 0.120396 0.3048)
			(stroke
				(width 0.1)
				(type default)
			)
			(layer "F.Fab")
		)
		(fp_line
			(start -0.12065 0.2794)
			(end -0.12065 0.3048)
			(stroke
				(width 0.1)
				(type default)
			)
			(layer "F.Fab")
		)
		(fp_line
			(start 0.120396 0.2794)
			(end -0.12065 0.2794)
			(stroke
				(width 0.1)
				(type default)
			)
			(layer "F.Fab")
		)
		(fp_line
			(start -0.12065 -0.2794)
			(end 0.12065 -0.2794)
			(stroke
				(width 0.1)
				(type default)
			)
			(layer "F.Fab")
		)
		(fp_line
			(start 0.12065 -0.2794)
			(end 0.12065 -0.3048)
			(stroke
				(width 0.1)
				(type default)
			)
			(layer "F.Fab")
		)
		(fp_line
			(start 0.12065 -0.3048)
			(end 0.67945 -0.3048)
			(stroke
				(width 0.1)
				(type default)
			)
			(layer "F.Fab")
		)
		(fp_line
			(start 0.67945 -0.3048)
			(end 0.67945 0.3048)
			(stroke
				(width 0.1)
				(type default)
			)
			(layer "F.Fab")
		)
		(fp_line
			(start -0.67945 -0.305054)
			(end -0.12065 -0.305054)
			(stroke
				(width 0.1)
				(type default)
			)
			(layer "F.Fab")
		)
		(fp_line
			(start -0.12065 -0.305054)
			(end -0.12065 -0.2794)
			(stroke
				(width 0.1)
				(type default)
			)
			(layer "F.Fab")
		)
		(pad "1" smd circle
			(at -0.40005 0 270)
			(size 0 0)
			(layers "F.Cu" "F.Mask" "F.Paste")
			(net "P3V3_AUX")
		)
		(pad "2" smd circle
			(at 0.40005 0 270)
			(size 0 0)
			(layers "F.Cu" "F.Mask" "F.Paste")
			(net "FM_THERMAL_ALERT_N")
		)
	)
	(footprint ""
		(layer "F.Cu")
		(at 94.1832 -401.1676 180)
		(property "Reference" "R1436"
			(at 0 0 180)
			(layer "F.SilkS")
			(hide yes)
			(effects
				(font
					(size 1.27 1.27)
				)
			)
		)
		(property "Value" ""
			(at 0 0 180)
			(layer "F.Fab")
			(effects
				(font
					(size 1.27 1.27)
				)
			)
		)
		(duplicate_pad_numbers_are_jumpers no)
		(fp_line
			(start 0.32512 0.175006)
			(end -0.32512 0.175006)
			(stroke
				(width 0.1)
				(type default)
			)
			(layer "F.Fab")
		)
		(fp_line
			(start 0.32512 -0.175006)
			(end 0.32512 0.175006)
			(stroke
				(width 0.1)
				(type default)
			)
			(layer "F.Fab")
		)
		(fp_line
			(start -0.32512 0.175006)
			(end -0.32512 -0.175006)
			(stroke
				(width 0.1)
				(type default)
			)
			(layer "F.Fab")
		)
		(fp_line
			(start -0.32512 -0.175006)
			(end 0.32512 -0.175006)
			(stroke
				(width 0.1)
				(type default)
			)
			(layer "F.Fab")
		)
		(pad "1" smd rect
			(at -0.2667 0 180)
			(size 0.3048 0.381)
			(layers "F.Cu" "F.Mask" "F.Paste")
			(net "P1V8_CPU1_RT_1D")
		)
		(pad "2" smd rect
			(at 0.2667 0)
			(size 0.3048 0.381)
			(layers "F.Cu" "F.Mask" "F.Paste")
			(net "SMB_RT_CPU1_P0_ROM_MUX_1D_SDA")
		)
	)
)
